(kicad_pcb
	(version 20260206)
	(generator "pcbnew")
	(generator_version "10.0")
	(general
		(thickness 1.6)
		(legacy_teardrops no)
	)
	(paper "A4")
	(title_block
		(title "Bryce Canyon_F.DPB_16315-1-OCP.brd")
		(comment 1 "Bryce Canyon / footprint 993 of 2223 (SAS1), pads 143-211 of 342")
	)
	(layers
		(0 "F.Cu" signal "TOP")
		(4 "In1.Cu" signal "L2GND")
		(6 "In2.Cu" signal "L3")
		(8 "In3.Cu" signal "L4GND")
		(10 "In4.Cu" signal "L5")
		(12 "In5.Cu" signal "L6VCC")
		(14 "In6.Cu" signal "L7VCC")
		(16 "In7.Cu" signal "L8")
		(18 "In8.Cu" signal "L9GND")
		(20 "In9.Cu" signal "L10")
		(22 "In10.Cu" signal "L11GND")
		(2 "B.Cu" signal "BOTTOM")
		(9 "F.Adhes" user "F.Adhesive")
		(11 "B.Adhes" user "B.Adhesive")
		(13 "F.Paste" user "Package Geometry/Pastemask Top")
		(15 "B.Paste" user "Package Geometry/Pastemask Bottom")
		(5 "F.SilkS" user "Ref Des/Silkscreen Top")
		(7 "B.SilkS" user "Ref Des/Silkscreen Bottom")
		(1 "F.Mask" user "Board Geometry/Soldermask Top")
		(3 "B.Mask" user "Board Geometry/Soldermask Bottom")
		(17 "Dwgs.User" user "User.Drawings")
		(19 "Cmts.User" user "User.Comments")
		(21 "Eco1.User" user "User.Eco1")
		(23 "Eco2.User" user "User.Eco2")
		(25 "Edge.Cuts" user "Board Geometry/Outline")
		(27 "Margin" user)
		(31 "F.CrtYd" user "Package Geometry/Place Bound Top")
		(29 "B.CrtYd" user "Package Geometry/Place Bound Bottom")
		(35 "F.Fab" user "Ref Des/Assembly Top")
		(33 "B.Fab" user "Ref Des/Assembly Bottom")
	)
	(footprint ""
		(layer "F.Cu")
		(at 287.83661 -357.705152 -90)
		(property "Reference" "SAS1"
			(at 0 0 270)
			(layer "F.SilkS")
			(hide yes)
			(effects
				(font
					(size 1.27 1.27)
				)
			)
		)
		(property "Value" "AMP-CONN342-10R-2-GP"
			(at 20.955 -16.7386 270)
			(unlocked yes)
			(layer "F.Fab")
			(hide yes)
			(effects
				(font
					(size 1.016 1.016)
					(thickness 0.1524)
				)
			)
		)
		(property "Device Type" "PREFIT-342P-668151H483"
			(at 20.955 -18.2626 270)
			(unlocked yes)
			(layer "F.Fab")
			(hide yes)
			(effects
				(font
					(size 1.016 1.016)
					(thickness 0.1524)
				)
			)
		)
		(duplicate_pad_numbers_are_jumpers no)
		(pad "D35" thru_hole circle
			(at 61.20003 4.99999 270)
			(size 0.762 0.762)
			(drill 0.359918)
			(layers "*.Cu" "*.Mask")
			(remove_unused_layers no)
			(net "DRIVE_A_35_ACT")
			(clearance 0.1651)
			(thermal_gap 0.1651)
		)
		(pad "D36" thru_hole circle
			(at 62.999874 5.999988 270)
			(size 0.762 0.762)
			(drill 0.359918)
			(layers "*.Cu" "*.Mask")
			(remove_unused_layers no)
			(net "SCC_A_FULL_PGOOD")
			(clearance 0.1651)
			(thermal_gap 0.1651)
		)
		(pad "E1" thru_hole circle
			(at 0 7.199884 270)
			(size 0.762 0.762)
			(drill 0.359918)
			(layers "*.Cu" "*.Mask")
			(remove_unused_layers no)
			(net "PHY_SCC_A_TO_DRV_A_0_DP")
			(clearance 0.1651)
			(thermal_gap 0.1651)
		)
		(pad "E2" thru_hole circle
			(at 1.800098 8.199882 270)
			(size 0.762 0.762)
			(drill 0.359918)
			(layers "*.Cu" "*.Mask")
			(remove_unused_layers no)
			(net "PHY_SCC_A_TO_DRV_A_1_DP")
			(clearance 0.1651)
			(thermal_gap 0.1651)
		)
		(pad "E3" thru_hole circle
			(at 3.599942 7.199884 270)
			(size 0.762 0.762)
			(drill 0.359918)
			(layers "*.Cu" "*.Mask")
			(remove_unused_layers no)
			(net "PHY_SCC_A_TO_DRV_A_2_DP")
			(clearance 0.1651)
			(thermal_gap 0.1651)
		)
		(pad "E4" thru_hole circle
			(at 5.40004 8.199882 270)
			(size 0.762 0.762)
			(drill 0.359918)
			(layers "*.Cu" "*.Mask")
			(remove_unused_layers no)
			(net "PHY_SCC_A_TO_DRV_A_3_DP")
			(clearance 0.1651)
			(thermal_gap 0.1651)
		)
		(pad "E5" thru_hole circle
			(at 7.199884 7.199884 270)
			(size 0.762 0.762)
			(drill 0.359918)
			(layers "*.Cu" "*.Mask")
			(remove_unused_layers no)
			(net "PHY_SCC_A_TO_DRV_A_4_DP")
			(clearance 0.1651)
			(thermal_gap 0.1651)
		)
		(pad "E6" thru_hole circle
			(at 8.999982 8.199882 270)
			(size 0.762 0.762)
			(drill 0.359918)
			(layers "*.Cu" "*.Mask")
			(remove_unused_layers no)
			(net "PHY_SCC_A_TO_DRV_A_5_DP")
			(clearance 0.1651)
			(thermal_gap 0.1651)
		)
		(pad "E7" thru_hole circle
			(at 10.80008 7.199884 270)
			(size 0.762 0.762)
			(drill 0.359918)
			(layers "*.Cu" "*.Mask")
			(remove_unused_layers no)
			(net "PHY_SCC_A_TO_DRV_A_11_DP")
			(clearance 0.1651)
			(thermal_gap 0.1651)
		)
		(pad "E8" thru_hole circle
			(at 12.599924 8.199882 270)
			(size 0.762 0.762)
			(drill 0.359918)
			(layers "*.Cu" "*.Mask")
			(remove_unused_layers no)
			(net "PHY_SCC_A_TO_DRV_A_10_DP")
			(clearance 0.1651)
			(thermal_gap 0.1651)
		)
		(pad "E9" thru_hole circle
			(at 14.400022 7.199884 270)
			(size 0.762 0.762)
			(drill 0.359918)
			(layers "*.Cu" "*.Mask")
			(remove_unused_layers no)
			(net "PHY_SCC_A_TO_DRV_A_9_DP")
			(clearance 0.1651)
			(thermal_gap 0.1651)
		)
		(pad "E10" thru_hole circle
			(at 16.20012 8.199882 270)
			(size 0.762 0.762)
			(drill 0.359918)
			(layers "*.Cu" "*.Mask")
			(remove_unused_layers no)
			(net "PHY_SCC_A_TO_DRV_A_8_DP")
			(clearance 0.1651)
			(thermal_gap 0.1651)
		)
		(pad "E11" thru_hole circle
			(at 17.999964 7.199884 270)
			(size 0.762 0.762)
			(drill 0.359918)
			(layers "*.Cu" "*.Mask")
			(remove_unused_layers no)
			(net "PHY_SCC_A_TO_DRV_A_7_DP")
			(clearance 0.1651)
			(thermal_gap 0.1651)
		)
		(pad "E12" thru_hole circle
			(at 19.800062 8.199882 270)
			(size 0.762 0.762)
			(drill 0.359918)
			(layers "*.Cu" "*.Mask")
			(remove_unused_layers no)
			(net "PHY_SCC_A_TO_DRV_A_6_DP")
			(clearance 0.1651)
			(thermal_gap 0.1651)
		)
		(pad "E13" thru_hole circle
			(at 21.599906 7.199884 270)
			(size 0.762 0.762)
			(drill 0.359918)
			(layers "*.Cu" "*.Mask")
			(remove_unused_layers no)
			(net "PHY_SCC_A_TO_DRV_A_12_DP")
			(clearance 0.1651)
			(thermal_gap 0.1651)
		)
		(pad "E14" thru_hole circle
			(at 23.400004 8.199882 270)
			(size 0.762 0.762)
			(drill 0.359918)
			(layers "*.Cu" "*.Mask")
			(remove_unused_layers no)
			(net "PHY_SCC_A_TO_DRV_A_13_DP")
			(clearance 0.1651)
			(thermal_gap 0.1651)
		)
		(pad "E15" thru_hole circle
			(at 25.200102 7.199884 270)
			(size 0.762 0.762)
			(drill 0.359918)
			(layers "*.Cu" "*.Mask")
			(remove_unused_layers no)
			(net "PHY_SCC_A_TO_DRV_A_14_DP")
			(clearance 0.1651)
			(thermal_gap 0.1651)
		)
		(pad "E16" thru_hole circle
			(at 26.999946 8.199882 270)
			(size 0.762 0.762)
			(drill 0.359918)
			(layers "*.Cu" "*.Mask")
			(remove_unused_layers no)
			(net "PHY_SCC_A_TO_DRV_A_15_DP")
			(clearance 0.1651)
			(thermal_gap 0.1651)
		)
		(pad "E17" thru_hole circle
			(at 28.800044 7.199884 270)
			(size 0.762 0.762)
			(drill 0.359918)
			(layers "*.Cu" "*.Mask")
			(remove_unused_layers no)
			(net "PHY_SCC_A_TO_DRV_A_16_DP")
			(clearance 0.1651)
			(thermal_gap 0.1651)
		)
		(pad "E18" thru_hole circle
			(at 30.599888 8.199882 270)
			(size 0.762 0.762)
			(drill 0.359918)
			(layers "*.Cu" "*.Mask")
			(remove_unused_layers no)
			(net "PHY_SCC_A_TO_DRV_A_17_DP")
			(clearance 0.1651)
			(thermal_gap 0.1651)
		)
		(pad "E19" thru_hole circle
			(at 32.399986 7.199884 270)
			(size 0.762 0.762)
			(drill 0.359918)
			(layers "*.Cu" "*.Mask")
			(remove_unused_layers no)
			(net "PHY_SCC_A_TO_DRV_A_23_DP")
			(clearance 0.1651)
			(thermal_gap 0.1651)
		)
		(pad "E20" thru_hole circle
			(at 34.200084 8.199882 270)
			(size 0.762 0.762)
			(drill 0.359918)
			(layers "*.Cu" "*.Mask")
			(remove_unused_layers no)
			(net "PHY_SCC_A_TO_DRV_A_22_DP")
			(clearance 0.1651)
			(thermal_gap 0.1651)
		)
		(pad "E21" thru_hole circle
			(at 35.999928 7.199884 270)
			(size 0.762 0.762)
			(drill 0.359918)
			(layers "*.Cu" "*.Mask")
			(remove_unused_layers no)
			(net "PHY_SCC_A_TO_DRV_A_21_DP")
			(clearance 0.1651)
			(thermal_gap 0.1651)
		)
		(pad "E22" thru_hole circle
			(at 37.800026 8.199882 270)
			(size 0.762 0.762)
			(drill 0.359918)
			(layers "*.Cu" "*.Mask")
			(remove_unused_layers no)
			(net "PHY_SCC_A_TO_DRV_A_20_DP")
			(clearance 0.1651)
			(thermal_gap 0.1651)
		)
		(pad "E23" thru_hole circle
			(at 39.600124 7.199884 270)
			(size 0.762 0.762)
			(drill 0.359918)
			(layers "*.Cu" "*.Mask")
			(remove_unused_layers no)
			(net "PHY_SCC_A_TO_DRV_A_19_DP")
			(clearance 0.1651)
			(thermal_gap 0.1651)
		)
		(pad "E24" thru_hole circle
			(at 41.399968 8.199882 270)
			(size 0.762 0.762)
			(drill 0.359918)
			(layers "*.Cu" "*.Mask")
			(remove_unused_layers no)
			(net "PHY_SCC_A_TO_DRV_A_18_DP")
			(clearance 0.1651)
			(thermal_gap 0.1651)
		)
		(pad "E25" thru_hole circle
			(at 43.200066 7.199884 270)
			(size 0.762 0.762)
			(drill 0.359918)
			(layers "*.Cu" "*.Mask")
			(remove_unused_layers no)
			(net "PHY_SCC_A_TO_DRV_A_24_DP")
			(clearance 0.1651)
			(thermal_gap 0.1651)
		)
		(pad "E26" thru_hole circle
			(at 44.99991 8.199882 270)
			(size 0.762 0.762)
			(drill 0.359918)
			(layers "*.Cu" "*.Mask")
			(remove_unused_layers no)
			(net "PHY_SCC_A_TO_DRV_A_25_DP")
			(clearance 0.1651)
			(thermal_gap 0.1651)
		)
		(pad "E27" thru_hole circle
			(at 46.800008 7.199884 270)
			(size 0.762 0.762)
			(drill 0.359918)
			(layers "*.Cu" "*.Mask")
			(remove_unused_layers no)
			(net "PHY_SCC_A_TO_DRV_A_26_DP")
			(clearance 0.1651)
			(thermal_gap 0.1651)
		)
		(pad "E28" thru_hole circle
			(at 48.600106 8.199882 270)
			(size 0.762 0.762)
			(drill 0.359918)
			(layers "*.Cu" "*.Mask")
			(remove_unused_layers no)
			(net "PHY_SCC_A_TO_DRV_A_27_DP")
			(clearance 0.1651)
			(thermal_gap 0.1651)
		)
		(pad "E29" thru_hole circle
			(at 50.39995 7.199884 270)
			(size 0.762 0.762)
			(drill 0.359918)
			(layers "*.Cu" "*.Mask")
			(remove_unused_layers no)
			(net "PHY_SCC_A_TO_DRV_A_28_DP")
			(clearance 0.1651)
			(thermal_gap 0.1651)
		)
		(pad "E30" thru_hole circle
			(at 52.200048 8.199882 270)
			(size 0.762 0.762)
			(drill 0.359918)
			(layers "*.Cu" "*.Mask")
			(remove_unused_layers no)
			(net "PHY_SCC_A_TO_DRV_A_29_DP")
			(clearance 0.1651)
			(thermal_gap 0.1651)
		)
		(pad "E31" thru_hole circle
			(at 53.999892 7.199884 270)
			(size 0.762 0.762)
			(drill 0.359918)
			(layers "*.Cu" "*.Mask")
			(remove_unused_layers no)
			(net "PHY_SCC_A_TO_DRV_A_35_DP")
			(clearance 0.1651)
			(thermal_gap 0.1651)
		)
		(pad "E32" thru_hole circle
			(at 55.79999 8.199882 270)
			(size 0.762 0.762)
			(drill 0.359918)
			(layers "*.Cu" "*.Mask")
			(remove_unused_layers no)
			(net "PHY_SCC_A_TO_DRV_A_34_DP")
			(clearance 0.1651)
			(thermal_gap 0.1651)
		)
		(pad "E33" thru_hole circle
			(at 57.600088 7.199884 270)
			(size 0.762 0.762)
			(drill 0.359918)
			(layers "*.Cu" "*.Mask")
			(remove_unused_layers no)
			(net "PHY_SCC_A_TO_DRV_A_33_DP")
			(clearance 0.1651)
			(thermal_gap 0.1651)
		)
		(pad "E34" thru_hole circle
			(at 59.399932 8.199882 270)
			(size 0.762 0.762)
			(drill 0.359918)
			(layers "*.Cu" "*.Mask")
			(remove_unused_layers no)
			(net "PHY_SCC_A_TO_DRV_A_32_DP")
			(clearance 0.1651)
			(thermal_gap 0.1651)
		)
		(pad "E35" thru_hole circle
			(at 61.20003 7.199884 270)
			(size 0.762 0.762)
			(drill 0.359918)
			(layers "*.Cu" "*.Mask")
			(remove_unused_layers no)
			(net "PHY_SCC_A_TO_DRV_A_31_DP")
			(clearance 0.1651)
			(thermal_gap 0.1651)
		)
		(pad "E36" thru_hole circle
			(at 62.999874 8.199882 270)
			(size 0.762 0.762)
			(drill 0.359918)
			(layers "*.Cu" "*.Mask")
			(remove_unused_layers no)
			(net "PHY_SCC_A_TO_DRV_A_30_DP")
			(clearance 0.1651)
			(thermal_gap 0.1651)
		)
		(pad "F1" thru_hole circle
			(at 0 8.599932 270)
			(size 0.762 0.762)
			(drill 0.359918)
			(layers "*.Cu" "*.Mask")
			(remove_unused_layers no)
			(net "PHY_SCC_A_TO_DRV_A_0_DN")
			(clearance 0.1651)
			(thermal_gap 0.1651)
		)
		(pad "F2" thru_hole circle
			(at 1.800098 9.59993 270)
			(size 0.762 0.762)
			(drill 0.359918)
			(layers "*.Cu" "*.Mask")
			(remove_unused_layers no)
			(net "PHY_SCC_A_TO_DRV_A_1_DN")
			(clearance 0.1651)
			(thermal_gap 0.1651)
		)
		(pad "F3" thru_hole circle
			(at 3.599942 8.599932 270)
			(size 0.762 0.762)
			(drill 0.359918)
			(layers "*.Cu" "*.Mask")
			(remove_unused_layers no)
			(net "PHY_SCC_A_TO_DRV_A_2_DN")
			(clearance 0.1651)
			(thermal_gap 0.1651)
		)
		(pad "F4" thru_hole circle
			(at 5.40004 9.59993 270)
			(size 0.762 0.762)
			(drill 0.359918)
			(layers "*.Cu" "*.Mask")
			(remove_unused_layers no)
			(net "PHY_SCC_A_TO_DRV_A_3_DN")
			(clearance 0.1651)
			(thermal_gap 0.1651)
		)
		(pad "F5" thru_hole circle
			(at 7.199884 8.599932 270)
			(size 0.762 0.762)
			(drill 0.359918)
			(layers "*.Cu" "*.Mask")
			(remove_unused_layers no)
			(net "PHY_SCC_A_TO_DRV_A_4_DN")
			(clearance 0.1651)
			(thermal_gap 0.1651)
		)
		(pad "F6" thru_hole circle
			(at 8.999982 9.59993 270)
			(size 0.762 0.762)
			(drill 0.359918)
			(layers "*.Cu" "*.Mask")
			(remove_unused_layers no)
			(net "PHY_SCC_A_TO_DRV_A_5_DN")
			(clearance 0.1651)
			(thermal_gap 0.1651)
		)
		(pad "F7" thru_hole circle
			(at 10.80008 8.599932 270)
			(size 0.762 0.762)
			(drill 0.359918)
			(layers "*.Cu" "*.Mask")
			(remove_unused_layers no)
			(net "PHY_SCC_A_TO_DRV_A_11_DN")
			(clearance 0.1651)
			(thermal_gap 0.1651)
		)
		(pad "F8" thru_hole circle
			(at 12.599924 9.59993 270)
			(size 0.762 0.762)
			(drill 0.359918)
			(layers "*.Cu" "*.Mask")
			(remove_unused_layers no)
			(net "PHY_SCC_A_TO_DRV_A_10_DN")
			(clearance 0.1651)
			(thermal_gap 0.1651)
		)
		(pad "F9" thru_hole circle
			(at 14.400022 8.599932 270)
			(size 0.762 0.762)
			(drill 0.359918)
			(layers "*.Cu" "*.Mask")
			(remove_unused_layers no)
			(net "PHY_SCC_A_TO_DRV_A_9_DN")
			(clearance 0.1651)
			(thermal_gap 0.1651)
		)
		(pad "F10" thru_hole circle
			(at 16.20012 9.59993 270)
			(size 0.762 0.762)
			(drill 0.359918)
			(layers "*.Cu" "*.Mask")
			(remove_unused_layers no)
			(net "PHY_SCC_A_TO_DRV_A_8_DN")
			(clearance 0.1651)
			(thermal_gap 0.1651)
		)
		(pad "F11" thru_hole circle
			(at 17.999964 8.599932 270)
			(size 0.762 0.762)
			(drill 0.359918)
			(layers "*.Cu" "*.Mask")
			(remove_unused_layers no)
			(net "PHY_SCC_A_TO_DRV_A_7_DN")
			(clearance 0.1651)
			(thermal_gap 0.1651)
		)
		(pad "F12" thru_hole circle
			(at 19.800062 9.59993 270)
			(size 0.762 0.762)
			(drill 0.359918)
			(layers "*.Cu" "*.Mask")
			(remove_unused_layers no)
			(net "PHY_SCC_A_TO_DRV_A_6_DN")
			(clearance 0.1651)
			(thermal_gap 0.1651)
		)
		(pad "F13" thru_hole circle
			(at 21.599906 8.599932 270)
			(size 0.762 0.762)
			(drill 0.359918)
			(layers "*.Cu" "*.Mask")
			(remove_unused_layers no)
			(net "PHY_SCC_A_TO_DRV_A_12_DN")
			(clearance 0.1651)
			(thermal_gap 0.1651)
		)
		(pad "F14" thru_hole circle
			(at 23.400004 9.59993 270)
			(size 0.762 0.762)
			(drill 0.359918)
			(layers "*.Cu" "*.Mask")
			(remove_unused_layers no)
			(net "PHY_SCC_A_TO_DRV_A_13_DN")
			(clearance 0.1651)
			(thermal_gap 0.1651)
		)
		(pad "F15" thru_hole circle
			(at 25.200102 8.599932 270)
			(size 0.762 0.762)
			(drill 0.359918)
			(layers "*.Cu" "*.Mask")
			(remove_unused_layers no)
			(net "PHY_SCC_A_TO_DRV_A_14_DN")
			(clearance 0.1651)
			(thermal_gap 0.1651)
		)
		(pad "F16" thru_hole circle
			(at 26.999946 9.59993 270)
			(size 0.762 0.762)
			(drill 0.359918)
			(layers "*.Cu" "*.Mask")
			(remove_unused_layers no)
			(net "PHY_SCC_A_TO_DRV_A_15_DN")
			(clearance 0.1651)
			(thermal_gap 0.1651)
		)
		(pad "F17" thru_hole circle
			(at 28.800044 8.599932 270)
			(size 0.762 0.762)
			(drill 0.359918)
			(layers "*.Cu" "*.Mask")
			(remove_unused_layers no)
			(net "PHY_SCC_A_TO_DRV_A_16_DN")
			(clearance 0.1651)
			(thermal_gap 0.1651)
		)
		(pad "F18" thru_hole circle
			(at 30.599888 9.59993 270)
			(size 0.762 0.762)
			(drill 0.359918)
			(layers "*.Cu" "*.Mask")
			(remove_unused_layers no)
			(net "PHY_SCC_A_TO_DRV_A_17_DN")
			(clearance 0.1651)
			(thermal_gap 0.1651)
		)
		(pad "F19" thru_hole circle
			(at 32.399986 8.599932 270)
			(size 0.762 0.762)
			(drill 0.359918)
			(layers "*.Cu" "*.Mask")
			(remove_unused_layers no)
			(net "PHY_SCC_A_TO_DRV_A_23_DN")
			(clearance 0.1651)
			(thermal_gap 0.1651)
		)
		(pad "F20" thru_hole circle
			(at 34.200084 9.59993 270)
			(size 0.762 0.762)
			(drill 0.359918)
			(layers "*.Cu" "*.Mask")
			(remove_unused_layers no)
			(net "PHY_SCC_A_TO_DRV_A_22_DN")
			(clearance 0.1651)
			(thermal_gap 0.1651)
		)
		(pad "F21" thru_hole circle
			(at 35.999928 8.599932 270)
			(size 0.762 0.762)
			(drill 0.359918)
			(layers "*.Cu" "*.Mask")
			(remove_unused_layers no)
			(net "PHY_SCC_A_TO_DRV_A_21_DN")
			(clearance 0.1651)
			(thermal_gap 0.1651)
		)
		(pad "F22" thru_hole circle
			(at 37.800026 9.59993 270)
			(size 0.762 0.762)
			(drill 0.359918)
			(layers "*.Cu" "*.Mask")
			(remove_unused_layers no)
			(net "PHY_SCC_A_TO_DRV_A_20_DN")
			(clearance 0.1651)
			(thermal_gap 0.1651)
		)
		(pad "F23" thru_hole circle
			(at 39.600124 8.599932 270)
			(size 0.762 0.762)
			(drill 0.359918)
			(layers "*.Cu" "*.Mask")
			(remove_unused_layers no)
			(net "PHY_SCC_A_TO_DRV_A_19_DN")
			(clearance 0.1651)
			(thermal_gap 0.1651)
		)
		(pad "F24" thru_hole circle
			(at 41.399968 9.59993 270)
			(size 0.762 0.762)
			(drill 0.359918)
			(layers "*.Cu" "*.Mask")
			(remove_unused_layers no)
			(net "PHY_SCC_A_TO_DRV_A_18_DN")
			(clearance 0.1651)
			(thermal_gap 0.1651)
		)
		(pad "F25" thru_hole circle
			(at 43.200066 8.599932 270)
			(size 0.762 0.762)
			(drill 0.359918)
			(layers "*.Cu" "*.Mask")
			(remove_unused_layers no)
			(net "PHY_SCC_A_TO_DRV_A_24_DN")
			(clearance 0.1651)
			(thermal_gap 0.1651)
		)
		(pad "F26" thru_hole circle
			(at 44.99991 9.59993 270)
			(size 0.762 0.762)
			(drill 0.359918)
			(layers "*.Cu" "*.Mask")
			(remove_unused_layers no)
			(net "PHY_SCC_A_TO_DRV_A_25_DN")
			(clearance 0.1651)
			(thermal_gap 0.1651)
		)
		(pad "F27" thru_hole circle
			(at 46.800008 8.599932 270)
			(size 0.762 0.762)
			(drill 0.359918)
			(layers "*.Cu" "*.Mask")
			(remove_unused_layers no)
			(net "PHY_SCC_A_TO_DRV_A_26_DN")
			(clearance 0.1651)
			(thermal_gap 0.1651)
		)
		(pad "F28" thru_hole circle
			(at 48.600106 9.59993 270)
			(size 0.762 0.762)
			(drill 0.359918)
			(layers "*.Cu" "*.Mask")
			(remove_unused_layers no)
			(net "PHY_SCC_A_TO_DRV_A_27_DN")
			(clearance 0.1651)
			(thermal_gap 0.1651)
		)
		(pad "F29" thru_hole circle
			(at 50.39995 8.599932 270)
			(size 0.762 0.762)
			(drill 0.359918)
			(layers "*.Cu" "*.Mask")
			(remove_unused_layers no)
			(net "PHY_SCC_A_TO_DRV_A_28_DN")
			(clearance 0.1651)
			(thermal_gap 0.1651)
		)
		(pad "F30" thru_hole circle
			(at 52.200048 9.59993 270)
			(size 0.762 0.762)
			(drill 0.359918)
			(layers "*.Cu" "*.Mask")
			(remove_unused_layers no)
			(net "PHY_SCC_A_TO_DRV_A_29_DN")
			(clearance 0.1651)
			(thermal_gap 0.1651)
		)
		(pad "F31" thru_hole circle
			(at 53.999892 8.599932 270)
			(size 0.762 0.762)
			(drill 0.359918)
			(layers "*.Cu" "*.Mask")
			(remove_unused_layers no)
			(net "PHY_SCC_A_TO_DRV_A_35_DN")
			(clearance 0.1651)
			(thermal_gap 0.1651)
		)
	)
)
